-- pcdb file, Rev:1.0 written by Allegro Design Entry HDL 16.2-s008 (v16-2-57Q) 4/6/2009 on Mon Aug 22 14:31:23 2011
#ISCELL
  mstr_standard drawing *
  *
#ISCELL
  mstr_standard synonym *
  page1_1p
